(kicad_pcb
	(version 20260206)
	(generator "pcbnew")
	(generator_version "10.0")
	(general
		(thickness 1.6)
		(legacy_teardrops no)
	)
	(paper "A4")
	(title_block
		(title "Bryce Canyon_R.DPB_16317-1_OCP.brd")
		(comment 1 "Bryce Canyon / footprints 1585-1593 of 2099")
	)
	(layers
		(0 "F.Cu" signal "TOP")
		(4 "In1.Cu" signal "L2GND")
		(6 "In2.Cu" signal "L3")
		(8 "In3.Cu" signal "L4VCC")
		(10 "In4.Cu" signal "L5VCC")
		(12 "In5.Cu" signal "L6")
		(14 "In6.Cu" signal "L7GND")
		(2 "B.Cu" signal "BOTTOM")
		(9 "F.Adhes" user "F.Adhesive")
		(11 "B.Adhes" user "B.Adhesive")
		(13 "F.Paste" user "Package Geometry/Pastemask Top")
		(15 "B.Paste" user "Package Geometry/Pastemask Bottom")
		(5 "F.SilkS" user "Ref Des/Silkscreen Top")
		(7 "B.SilkS" user "Ref Des/Silkscreen Bottom")
		(1 "F.Mask" user "Board Geometry/Soldermask Top")
		(3 "B.Mask" user "Board Geometry/Soldermask Bottom")
		(17 "Dwgs.User" user "User.Drawings")
		(19 "Cmts.User" user "User.Comments")
		(21 "Eco1.User" user "User.Eco1")
		(23 "Eco2.User" user "User.Eco2")
		(25 "Edge.Cuts" user "Board Geometry/Outline")
		(27 "Margin" user)
		(31 "F.CrtYd" user "Package Geometry/Place Bound Top")
		(29 "B.CrtYd" user "Package Geometry/Place Bound Bottom")
		(35 "F.Fab" user "Ref Des/Assembly Top")
		(33 "B.Fab" user "Ref Des/Assembly Bottom")
	)
	(footprint ""
		(layer "F.Cu")
		(at 158.708852 -18.750026 -90)
		(property "Reference" "VIA58"
			(at 0 0 270)
			(layer "F.SilkS")
			(hide yes)
			(effects
				(font
					(size 1.27 1.27)
				)
			)
		)
		(property "Value" "100OHM-8L-2D36MM-L16-GP"
			(at -3.4036 -0.4572 270)
			(unlocked yes)
			(layer "F.Fab")
			(hide yes)
			(effects
				(font
					(size 1.016 1.016)
					(thickness 0.1524)
				)
			)
		)
		(property "Device Type" "VIA-PCIE-4P-427097"
			(at -3.4036 -1.9812 270)
			(unlocked yes)
			(layer "F.Fab")
			(hide yes)
			(effects
				(font
					(size 1.016 1.016)
					(thickness 0.1524)
				)
			)
		)
		(duplicate_pad_numbers_are_jumpers no)
		(fp_rect
			(start -2.1336 0.4826)
			(end 2.1336 -0.4826)
			(stroke
				(width 0)
				(type default)
			)
			(fill no)
			(layer "F.CrtYd")
		)
		(fp_rect
			(start -2.1336 0.4826)
			(end 2.1336 -0.4826)
			(stroke
				(width 0)
				(type default)
			)
			(fill no)
			(layer "F.Fab")
		)
		(pad "1" thru_hole circle
			(at -1.651 0 270)
			(size 0.508 0.508)
			(drill 0.254)
			(layers "*.Cu" "*.Mask")
			(remove_unused_layers no)
			(net "GND")
			(clearance 0.2286)
			(thermal_gap 0.2286)
		)
		(pad "2" thru_hole circle
			(at -0.635 0 270)
			(size 0.508 0.508)
			(drill 0.254)
			(layers "*.Cu" "*.Mask")
			(remove_unused_layers no)
			(net "PHY_DRV_B_TO_SCC_B_28_DP")
			(clearance 0.2286)
			(thermal_gap 0.2286)
		)
		(pad "3" thru_hole circle
			(at 0.635 0 270)
			(size 0.508 0.508)
			(drill 0.254)
			(layers "*.Cu" "*.Mask")
			(remove_unused_layers no)
			(net "PHY_DRV_B_TO_SCC_B_28_DN")
			(clearance 0.2286)
			(thermal_gap 0.2286)
		)
		(pad "4" thru_hole circle
			(at 1.651 0 270)
			(size 0.508 0.508)
			(drill 0.254)
			(layers "*.Cu" "*.Mask")
			(remove_unused_layers no)
			(net "GND")
			(clearance 0.2286)
			(thermal_gap 0.2286)
		)
	)
	(footprint ""
		(layer "F.Cu")
		(at 34.763964 -269.705074)
		(property "Reference" "TP201"
			(at 0 0 0)
			(layer "F.SilkS")
			(hide yes)
			(effects
				(font
					(size 1.27 1.27)
				)
			)
		)
		(property "Value" "*"
			(at -0.0508 -1.6764 0)
			(unlocked yes)
			(layer "F.Fab")
			(hide yes)
			(effects
				(font
					(size 1.016 1.016)
					(thickness 0.1524)
				)
			)
		)
		(property "Device Type" "TPAD32"
			(at -0.0508 -3.2004 0)
			(unlocked yes)
			(layer "F.Fab")
			(hide yes)
			(effects
				(font
					(size 1.016 1.016)
					(thickness 0.1524)
				)
			)
		)
		(duplicate_pad_numbers_are_jumpers no)
		(fp_poly
			(pts
				(arc
					(start 0.4064 0)
					(mid -0.4064 0)
					(end 0.4064 0)
				)
			)
			(stroke
				(width 0)
				(type default)
			)
			(fill no)
			(layer "F.CrtYd")
		)
		(fp_poly
			(pts
				(arc
					(start 0.7112 0)
					(mid -0.7112 0)
					(end 0.7112 0)
				)
			)
			(stroke
				(width 0)
				(type default)
			)
			(fill no)
			(layer "F.Fab")
		)
		(pad "1" smd circle
			(at 0 0)
			(size 0.8128 0.8128)
			(layers "F.Cu" "F.Mask" "F.Paste")
			(net "ACT_HDD_0")
		)
	)
	(footprint ""
		(layer "F.Cu")
		(at 209.03946 -165.40226 -90)
		(property "Reference" "R61"
			(at 0 0 270)
			(layer "F.SilkS")
			(hide yes)
			(effects
				(font
					(size 1.27 1.27)
				)
			)
		)
		(property "Value" "0R2J-2-GP"
			(at 0.064008 -3.993896 270)
			(unlocked yes)
			(layer "F.Fab")
			(hide yes)
			(effects
				(font
					(size 1.016 1.016)
					(thickness 0.1524)
				)
			)
		)
		(property "Device Type" "R402H16"
			(at 0.064008 -5.517896 270)
			(unlocked yes)
			(layer "F.Fab")
			(hide yes)
			(effects
				(font
					(size 1.016 1.016)
					(thickness 0.1524)
				)
			)
		)
		(duplicate_pad_numbers_are_jumpers no)
		(fp_line
			(start -0.508 -0.9398)
			(end -0.508 0.9398)
			(stroke
				(width 0.1524)
				(type default)
			)
			(layer "F.SilkS")
		)
		(fp_line
			(start 0.508 -0.9398)
			(end -0.508 -0.9398)
			(stroke
				(width 0.1524)
				(type default)
			)
			(layer "F.SilkS")
		)
		(fp_rect
			(start -0.508 0.9398)
			(end 0.508 -0.9398)
			(stroke
				(width 0)
				(type default)
			)
			(fill no)
			(layer "F.CrtYd")
		)
		(fp_rect
			(start -0.508 0.9398)
			(end 0.508 -0.9398)
			(stroke
				(width 0)
				(type default)
			)
			(fill no)
			(layer "F.Fab")
		)
		(pad "1" smd custom
			(at 0 -0.4445 270)
			(size 0.1397 0.1397)
			(layers "F.Cu" "F.Mask" "F.Paste")
			(net "IO_EXP6_SCL")
			(options
				(clearance outline)
				(anchor circle)
			)
			(primitives
				(gr_poly
					(pts
						(arc
							(start -0.1778 -0.2794)
							(mid -0.249642 -0.249642)
							(end -0.2794 -0.1778)
						)
						(arc
							(start -0.2794 0.1778)
							(mid -0.249642 0.249642)
							(end -0.1778 0.2794)
						)
						(arc
							(start 0.1778 0.2794)
							(mid 0.249642 0.249642)
							(end 0.2794 0.1778)
						)
						(arc
							(start 0.2794 -0.1778)
							(mid 0.249642 -0.249642)
							(end 0.1778 -0.2794)
						)
					)
					(width 0)
					(fill yes)
				)
			)
		)
		(pad "2" smd custom
			(at 0 0.4445 270)
			(size 0.1397 0.1397)
			(layers "F.Cu" "F.Mask" "F.Paste")
			(net "I2C_DRIVE_B_INS_SCL")
			(options
				(clearance outline)
				(anchor circle)
			)
			(primitives
				(gr_poly
					(pts
						(arc
							(start -0.1778 -0.2794)
							(mid -0.249642 -0.249642)
							(end -0.2794 -0.1778)
						)
						(arc
							(start -0.2794 0.1778)
							(mid -0.249642 0.249642)
							(end -0.1778 0.2794)
						)
						(arc
							(start 0.1778 0.2794)
							(mid 0.249642 0.249642)
							(end 0.2794 0.1778)
						)
						(arc
							(start 0.2794 -0.1778)
							(mid 0.249642 -0.249642)
							(end 0.1778 -0.2794)
						)
					)
					(width 0)
					(fill yes)
				)
			)
		)
	)
	(footprint ""
		(layer "F.Cu")
		(at 264.033 -224.79)
		(property "Reference" "R3"
			(at 0 0 0)
			(layer "F.SilkS")
			(hide yes)
			(effects
				(font
					(size 1.27 1.27)
				)
			)
		)
		(property "Value" "100KR2F-L1-GP"
			(at 0.064008 -3.993896 0)
			(unlocked yes)
			(layer "F.Fab")
			(hide yes)
			(effects
				(font
					(size 1.016 1.016)
					(thickness 0.1524)
				)
			)
		)
		(property "Device Type" "R402H16"
			(at 0.064008 -5.517896 0)
			(unlocked yes)
			(layer "F.Fab")
			(hide yes)
			(effects
				(font
					(size 1.016 1.016)
					(thickness 0.1524)
				)
			)
		)
		(duplicate_pad_numbers_are_jumpers no)
		(fp_line
			(start -0.508 -0.9398)
			(end -0.508 0.9398)
			(stroke
				(width 0.1524)
				(type default)
			)
			(layer "F.SilkS")
		)
		(fp_line
			(start 0.508 -0.9398)
			(end -0.508 -0.9398)
			(stroke
				(width 0.1524)
				(type default)
			)
			(layer "F.SilkS")
		)
		(fp_rect
			(start -0.508 0.9398)
			(end 0.508 -0.9398)
			(stroke
				(width 0)
				(type default)
			)
			(fill no)
			(layer "F.CrtYd")
		)
		(fp_rect
			(start -0.508 0.9398)
			(end 0.508 -0.9398)
			(stroke
				(width 0)
				(type default)
			)
			(fill no)
			(layer "F.Fab")
		)
		(pad "1" smd custom
			(at 0 -0.4445)
			(size 0.1397 0.1397)
			(layers "F.Cu" "F.Mask" "F.Paste")
			(net "P3V3_STBY_B")
			(options
				(clearance outline)
				(anchor circle)
			)
			(primitives
				(gr_poly
					(pts
						(arc
							(start -0.1778 -0.2794)
							(mid -0.249642 -0.249642)
							(end -0.2794 -0.1778)
						)
						(arc
							(start -0.2794 0.1778)
							(mid -0.249642 0.249642)
							(end -0.1778 0.2794)
						)
						(arc
							(start 0.1778 0.2794)
							(mid 0.249642 0.249642)
							(end 0.2794 0.1778)
						)
						(arc
							(start 0.2794 -0.1778)
							(mid 0.249642 -0.249642)
							(end 0.1778 -0.2794)
						)
					)
					(width 0)
					(fill yes)
				)
			)
		)
		(pad "2" smd custom
			(at 0 0.4445)
			(size 0.1397 0.1397)
			(layers "F.Cu" "F.Mask" "F.Paste")
			(net "SCC_B_INS_N")
			(options
				(clearance outline)
				(anchor circle)
			)
			(primitives
				(gr_poly
					(pts
						(arc
							(start -0.1778 -0.2794)
							(mid -0.249642 -0.249642)
							(end -0.2794 -0.1778)
						)
						(arc
							(start -0.2794 0.1778)
							(mid -0.249642 0.249642)
							(end -0.1778 0.2794)
						)
						(arc
							(start 0.1778 0.2794)
							(mid 0.249642 0.249642)
							(end 0.2794 0.1778)
						)
						(arc
							(start 0.2794 -0.1778)
							(mid 0.249642 -0.249642)
							(end 0.1778 -0.2794)
						)
					)
					(width 0)
					(fill yes)
				)
			)
		)
	)
	(footprint ""
		(layer "F.Cu")
		(at 457.0476 -16.0528 90)
		(property "Reference" "R860"
			(at 0 0 90)
			(layer "F.SilkS")
			(hide yes)
			(effects
				(font
					(size 1.27 1.27)
				)
			)
		)
		(property "Value" "1KR2F-3-GP"
			(at 0.064008 -3.993896 90)
			(unlocked yes)
			(layer "F.Fab")
			(hide yes)
			(effects
				(font
					(size 1.016 1.016)
					(thickness 0.1524)
				)
			)
		)
		(property "Device Type" "R402H16"
			(at 0.064008 -5.517896 90)
			(unlocked yes)
			(layer "F.Fab")
			(hide yes)
			(effects
				(font
					(size 1.016 1.016)
					(thickness 0.1524)
				)
			)
		)
		(duplicate_pad_numbers_are_jumpers no)
		(fp_line
			(start 0.508 -0.9398)
			(end -0.508 -0.9398)
			(stroke
				(width 0.1524)
				(type default)
			)
			(layer "F.SilkS")
		)
		(fp_line
			(start -0.508 -0.9398)
			(end -0.508 0.9398)
			(stroke
				(width 0.1524)
				(type default)
			)
			(layer "F.SilkS")
		)
		(fp_rect
			(start -0.508 0.9398)
			(end 0.508 -0.9398)
			(stroke
				(width 0)
				(type default)
			)
			(fill no)
			(layer "F.CrtYd")
		)
		(fp_rect
			(start -0.508 0.9398)
			(end 0.508 -0.9398)
			(stroke
				(width 0)
				(type default)
			)
			(fill no)
			(layer "F.Fab")
		)
		(pad "1" smd custom
			(at 0 -0.4445 90)
			(size 0.1397 0.1397)
			(layers "F.Cu" "F.Mask" "F.Paste")
			(net "P3V3_STBY_B")
			(options
				(clearance outline)
				(anchor circle)
			)
			(primitives
				(gr_poly
					(pts
						(arc
							(start -0.1778 -0.2794)
							(mid -0.249642 -0.249642)
							(end -0.2794 -0.1778)
						)
						(arc
							(start -0.2794 0.1778)
							(mid -0.249642 0.249642)
							(end -0.1778 0.2794)
						)
						(arc
							(start 0.1778 0.2794)
							(mid 0.249642 0.249642)
							(end 0.2794 0.1778)
						)
						(arc
							(start 0.2794 -0.1778)
							(mid 0.249642 -0.249642)
							(end 0.1778 -0.2794)
						)
					)
					(width 0)
					(fill yes)
				)
			)
		)
		(pad "2" smd custom
			(at 0 0.4445 90)
			(size 0.1397 0.1397)
			(layers "F.Cu" "F.Mask" "F.Paste")
			(net "SW_PWR_R_HDD34")
			(options
				(clearance outline)
				(anchor circle)
			)
			(primitives
				(gr_poly
					(pts
						(arc
							(start -0.1778 -0.2794)
							(mid -0.249642 -0.249642)
							(end -0.2794 -0.1778)
						)
						(arc
							(start -0.2794 0.1778)
							(mid -0.249642 0.249642)
							(end -0.1778 0.2794)
						)
						(arc
							(start 0.1778 0.2794)
							(mid 0.249642 0.249642)
							(end 0.2794 0.1778)
						)
						(arc
							(start 0.2794 -0.1778)
							(mid 0.249642 -0.249642)
							(end 0.1778 -0.2794)
						)
					)
					(width 0)
					(fill yes)
				)
			)
		)
	)
	(footprint ""
		(layer "F.Cu")
		(at 64.013334 -129.66065 90)
		(property "Reference" "C198"
			(at 0 0 90)
			(layer "F.SilkS")
			(hide yes)
			(effects
				(font
					(size 1.27 1.27)
				)
			)
		)
		(property "Value" "SCD01U16V1KX-GP"
			(at -2.8321 -1.7399 90)
			(unlocked yes)
			(layer "F.Fab")
			(hide yes)
			(effects
				(font
					(size 1.016 1.016)
					(thickness 0.1524)
				)
			)
		)
		(property "Device Type" "C0201H13"
			(at -2.8321 -3.2639 90)
			(unlocked yes)
			(layer "F.Fab")
			(hide yes)
			(effects
				(font
					(size 1.016 1.016)
					(thickness 0.1524)
				)
			)
		)
		(duplicate_pad_numbers_are_jumpers no)
		(fp_rect
			(start -0.2794 0.6477)
			(end 0.2794 -0.6477)
			(stroke
				(width 0)
				(type default)
			)
			(fill no)
			(layer "F.CrtYd")
		)
		(fp_rect
			(start -0.2794 0.6477)
			(end 0.2794 -0.6477)
			(stroke
				(width 0)
				(type default)
			)
			(fill no)
			(layer "F.Fab")
		)
		(pad "1" smd custom
			(at 0 -0.2794 90)
			(size 0.0762 0.0762)
			(layers "F.Cu" "F.Mask" "F.Paste")
			(net "SAS_HDD_RX_P13")
			(options
				(clearance outline)
				(anchor circle)
			)
			(primitives
				(gr_poly
					(pts
						(arc
							(start 0.1524 -0.127)
							(mid 0.137521 -0.162921)
							(end 0.1016 -0.1778)
						)
						(arc
							(start -0.1016 -0.1778)
							(mid -0.137521 -0.162921)
							(end -0.1524 -0.127)
						)
						(arc
							(start -0.1524 0.127)
							(mid -0.137521 0.162921)
							(end -0.1016 0.1778)
						)
						(arc
							(start 0.1016 0.1778)
							(mid 0.137521 0.162921)
							(end 0.1524 0.127)
						)
					)
					(width 0)
					(fill yes)
				)
			)
		)
		(pad "2" smd custom
			(at 0 0.2794 90)
			(size 0.0762 0.0762)
			(layers "F.Cu" "F.Mask" "F.Paste")
			(net "PHY_SCC_B_TO_DRV_B_13_DP")
			(options
				(clearance outline)
				(anchor circle)
			)
			(primitives
				(gr_poly
					(pts
						(arc
							(start 0.1524 -0.127)
							(mid 0.137521 -0.162921)
							(end 0.1016 -0.1778)
						)
						(arc
							(start -0.1016 -0.1778)
							(mid -0.137521 -0.162921)
							(end -0.1524 -0.127)
						)
						(arc
							(start -0.1524 0.127)
							(mid -0.137521 0.162921)
							(end -0.1016 0.1778)
						)
						(arc
							(start 0.1016 0.1778)
							(mid 0.137521 0.162921)
							(end 0.1524 0.127)
						)
					)
					(width 0)
					(fill yes)
				)
			)
		)
	)
	(footprint ""
		(layer "F.Cu")
		(at 117.221 -13.081 -90)
		(property "Reference" "D27"
			(at 0 0 270)
			(layer "F.SilkS")
			(hide yes)
			(effects
				(font
					(size 1.27 1.27)
				)
			)
		)
		(property "Value" "RB551V30-GP"
			(at 0 -6.7818 270)
			(unlocked yes)
			(layer "F.Fab")
			(hide yes)
			(effects
				(font
					(size 1.016 1.016)
					(thickness 0.1524)
				)
			)
		)
		(property "Device Type" "SOD323AKH38"
			(at 0 -8.6868 270)
			(unlocked yes)
			(layer "F.Fab")
			(hide yes)
			(effects
				(font
					(size 1.016 1.016)
					(thickness 0.1524)
				)
			)
		)
		(duplicate_pad_numbers_are_jumpers no)
		(fp_line
			(start -0.889 2.159)
			(end -0.889 -1.9304)
			(stroke
				(width 0.1524)
				(type default)
			)
			(layer "F.SilkS")
		)
		(fp_line
			(start 0.889 2.159)
			(end -0.889 2.159)
			(stroke
				(width 0.1524)
				(type default)
			)
			(layer "F.SilkS")
		)
		(fp_line
			(start 0.762 2.0574)
			(end -0.762 2.0574)
			(stroke
				(width 0.508)
				(type default)
			)
			(layer "F.SilkS")
		)
		(fp_line
			(start -0.889 -1.9304)
			(end 0.889 -1.9304)
			(stroke
				(width 0.1524)
				(type default)
			)
			(layer "F.SilkS")
		)
		(fp_line
			(start 0.889 -1.9304)
			(end 0.889 2.159)
			(stroke
				(width 0.1524)
				(type default)
			)
			(layer "F.SilkS")
		)
		(fp_rect
			(start -1.016 2.3114)
			(end 1.016 -2.0066)
			(stroke
				(width 0)
				(type default)
			)
			(fill no)
			(layer "F.CrtYd")
		)
		(fp_poly
			(pts
				(xy -1.016 -2.0066) (xy 1.016 -2.0066) (xy 1.016 2.3114) (xy -1.016 2.3114)
			)
			(stroke
				(width 0)
				(type default)
			)
			(fill no)
			(layer "F.Fab")
		)
		(pad "A" smd rect
			(at 0 -1.143 270)
			(size 0.5588 1.016)
			(layers "F.Cu" "F.Mask" "F.Paste")
			(net "SW_HDD_R27")
		)
		(pad "K" smd rect
			(at 0 1.143 270)
			(size 0.5588 1.016)
			(layers "F.Cu" "F.Mask" "F.Paste")
			(net "SW_HDD_N27")
		)
	)
	(footprint ""
		(layer "F.Cu")
		(at 179.8828 -37.8206)
		(property "Reference" "TP166"
			(at 0 0 0)
			(layer "F.SilkS")
			(hide yes)
			(effects
				(font
					(size 1.27 1.27)
				)
			)
		)
		(property "Value" "*"
			(at -0.0508 -1.6764 0)
			(unlocked yes)
			(layer "F.Fab")
			(hide yes)
			(effects
				(font
					(size 1.016 1.016)
					(thickness 0.1524)
				)
			)
		)
		(property "Device Type" "TPAD32"
			(at -0.0508 -3.2004 0)
			(unlocked yes)
			(layer "F.Fab")
			(hide yes)
			(effects
				(font
					(size 1.016 1.016)
					(thickness 0.1524)
				)
			)
		)
		(duplicate_pad_numbers_are_jumpers no)
		(fp_poly
			(pts
				(arc
					(start 0.4064 0)
					(mid -0.4064 0)
					(end 0.4064 0)
				)
			)
			(stroke
				(width 0)
				(type default)
			)
			(fill no)
			(layer "F.CrtYd")
		)
		(fp_poly
			(pts
				(arc
					(start 0.7112 0)
					(mid -0.7112 0)
					(end 0.7112 0)
				)
			)
			(stroke
				(width 0)
				(type default)
			)
			(fill no)
			(layer "F.Fab")
		)
		(pad "1" smd circle
			(at 0 0)
			(size 0.8128 0.8128)
			(layers "F.Cu" "F.Mask" "F.Paste")
			(net "ACT_HDD_29")
		)
	)
	(footprint ""
		(layer "F.Cu")
		(at 337.312 -248.793 90)
		(property "Reference" "D6"
			(at 0 0 90)
			(layer "F.SilkS")
			(hide yes)
			(effects
				(font
					(size 1.27 1.27)
				)
			)
		)
		(property "Value" "RB551V30-GP"
			(at 0 -6.7818 90)
			(unlocked yes)
			(layer "F.Fab")
			(hide yes)
			(effects
				(font
					(size 1.016 1.016)
					(thickness 0.1524)
				)
			)
		)
		(property "Device Type" "SOD323AKH38"
			(at 0 -8.6868 90)
			(unlocked yes)
			(layer "F.Fab")
			(hide yes)
			(effects
				(font
					(size 1.016 1.016)
					(thickness 0.1524)
				)
			)
		)
		(duplicate_pad_numbers_are_jumpers no)
		(fp_line
			(start 0.889 -1.9304)
			(end 0.889 2.159)
			(stroke
				(width 0.1524)
				(type default)
			)
			(layer "F.SilkS")
		)
		(fp_line
			(start -0.889 -1.9304)
			(end 0.889 -1.9304)
			(stroke
				(width 0.1524)
				(type default)
			)
			(layer "F.SilkS")
		)
		(fp_line
			(start 0.762 2.0574)
			(end -0.762 2.0574)
			(stroke
				(width 0.508)
				(type default)
			)
			(layer "F.SilkS")
		)
		(fp_line
			(start 0.889 2.159)
			(end -0.889 2.159)
			(stroke
				(width 0.1524)
				(type default)
			)
			(layer "F.SilkS")
		)
		(fp_line
			(start -0.889 2.159)
			(end -0.889 -1.9304)
			(stroke
				(width 0.1524)
				(type default)
			)
			(layer "F.SilkS")
		)
		(fp_rect
			(start -1.016 2.3114)
			(end 1.016 -2.0066)
			(stroke
				(width 0)
				(type default)
			)
			(fill no)
			(layer "F.CrtYd")
		)
		(fp_poly
			(pts
				(xy -1.016 -2.0066) (xy 1.016 -2.0066) (xy 1.016 2.3114) (xy -1.016 2.3114)
			)
			(stroke
				(width 0)
				(type default)
			)
			(fill no)
			(layer "F.Fab")
		)
		(pad "A" smd rect
			(at 0 -1.143 90)
			(size 0.5588 1.016)
			(layers "F.Cu" "F.Mask" "F.Paste")
			(net "SW_HDD_R6")
		)
		(pad "K" smd rect
			(at 0 1.143 90)
			(size 0.5588 1.016)
			(layers "F.Cu" "F.Mask" "F.Paste")
			(net "SW_HDD_N6")
		)
	)
)
